(kicad_pcb
	(version 20260206)
	(generator "pcbnew")
	(generator_version "10.0")
	(general
		(thickness 1.6)
		(legacy_teardrops no)
	)
	(paper "A4")
	(title_block
		(title "Bryce Canyon_Front Panel_16369-1_OCP.brd")
		(comment 1 "Bryce Canyon / footprints 88-94 of 154")
	)
	(layers
		(0 "F.Cu" signal "TOP")
		(4 "In1.Cu" signal "L2GND")
		(6 "In2.Cu" signal "L3VCC")
		(2 "B.Cu" signal "BOTTOM")
		(9 "F.Adhes" user "F.Adhesive")
		(11 "B.Adhes" user "B.Adhesive")
		(13 "F.Paste" user "Package Geometry/Pastemask Top")
		(15 "B.Paste" user "Package Geometry/Pastemask Bottom")
		(5 "F.SilkS" user "Ref Des/Silkscreen Top")
		(7 "B.SilkS" user "Ref Des/Silkscreen Bottom")
		(1 "F.Mask" user "Board Geometry/Soldermask Top")
		(3 "B.Mask" user "Board Geometry/Soldermask Bottom")
		(17 "Dwgs.User" user "User.Drawings")
		(19 "Cmts.User" user "User.Comments")
		(21 "Eco1.User" user "User.Eco1")
		(23 "Eco2.User" user "User.Eco2")
		(25 "Edge.Cuts" user "Board Geometry/Outline")
		(27 "Margin" user)
		(31 "F.CrtYd" user "Package Geometry/Place Bound Top")
		(29 "B.CrtYd" user "Package Geometry/Place Bound Bottom")
		(35 "F.Fab" user "Ref Des/Assembly Top")
		(33 "B.Fab" user "Ref Des/Assembly Bottom")
	)
	(footprint ""
		(layer "F.Cu")
		(at 7.112 -20.447 -90)
		(property "Reference" "U9"
			(at 0 0 270)
			(layer "F.SilkS")
			(hide yes)
			(effects
				(font
					(size 1.27 1.27)
				)
			)
		)
		(property "Value" "PCA9306DCTT-GP"
			(at 0 -11.6332 270)
			(unlocked yes)
			(layer "F.Fab")
			(hide yes)
			(effects
				(font
					(size 1.016 1.016)
					(thickness 0.1524)
				)
			)
		)
		(property "Device Type" "SSOIC8H52"
			(at 0 -13.1572 270)
			(unlocked yes)
			(layer "F.Fab")
			(hide yes)
			(effects
				(font
					(size 1.016 1.016)
					(thickness 0.1524)
				)
			)
		)
		(duplicate_pad_numbers_are_jumpers no)
		(fp_line
			(start -1.524 0.5842)
			(end -1.524 2.286)
			(stroke
				(width 0.508)
				(type default)
			)
			(layer "F.SilkS")
		)
		(fp_line
			(start 1.0668 0.5842)
			(end -1.524 0.5842)
			(stroke
				(width 0.1524)
				(type default)
			)
			(layer "F.SilkS")
		)
		(fp_line
			(start -1.397 0)
			(end -1.7018 0.3048)
			(stroke
				(width 0.1524)
				(type default)
			)
			(layer "F.SilkS")
		)
		(fp_line
			(start -1.397 0)
			(end -1.7018 -0.3048)
			(stroke
				(width 0.1524)
				(type default)
			)
			(layer "F.SilkS")
		)
		(fp_line
			(start -1.7018 -0.5842)
			(end -1.7018 2.286)
			(stroke
				(width 0.1524)
				(type default)
			)
			(layer "F.SilkS")
		)
		(fp_line
			(start -1.7018 -0.5842)
			(end 1.0668 -0.5842)
			(stroke
				(width 0.1524)
				(type default)
			)
			(layer "F.SilkS")
		)
		(fp_line
			(start 1.0668 -0.5842)
			(end 1.0668 0.5842)
			(stroke
				(width 0.1524)
				(type default)
			)
			(layer "F.SilkS")
		)
		(fp_poly
			(pts
				(xy -1.1684 -0.5842) (xy 1.0668 -0.5842) (xy 1.0668 0.5842) (xy -1.1684 0.5842)
			)
			(stroke
				(width 0)
				(type default)
			)
			(fill yes)
			(layer "F.SilkS")
		)
		(fp_poly
			(pts
				(xy -1.778 2.54) (xy 1.778 2.54) (xy 1.778 -2.54) (xy -1.778 -2.54)
			)
			(stroke
				(width 0)
				(type default)
			)
			(fill no)
			(layer "F.CrtYd")
		)
		(fp_poly
			(pts
				(xy -1.778 -2.54) (xy 1.778 -2.54) (xy 1.778 2.54) (xy -1.778 2.54)
			)
			(stroke
				(width 0)
				(type default)
			)
			(fill no)
			(layer "F.Fab")
		)
		(pad "1" smd rect
			(at -0.97536 1.6256 270)
			(size 0.3556 1.524)
			(layers "F.Cu" "F.Mask" "F.Paste")
			(net "GND")
		)
		(pad "2" smd rect
			(at -0.32512 1.6256 270)
			(size 0.3556 1.524)
			(layers "F.Cu" "F.Mask" "F.Paste")
			(net "P3V3_STBY_A")
		)
		(pad "3" smd rect
			(at 0.32512 1.6256 270)
			(size 0.3556 1.524)
			(layers "F.Cu" "F.Mask" "F.Paste")
			(net "I2C_DEBUG_A_SCL")
		)
		(pad "4" smd rect
			(at 0.97536 1.6256 270)
			(size 0.3556 1.524)
			(layers "F.Cu" "F.Mask" "F.Paste")
			(net "I2C_DEBUG_A_SDA")
		)
		(pad "5" smd rect
			(at 0.97536 -1.6256 270)
			(size 0.3556 1.524)
			(layers "F.Cu" "F.Mask" "F.Paste")
			(net "I2C_DEBUG_A_SDA_L")
		)
		(pad "6" smd rect
			(at 0.32512 -1.6256 270)
			(size 0.3556 1.524)
			(layers "F.Cu" "F.Mask" "F.Paste")
			(net "I2C_DEBUG_A_SCL_L")
		)
		(pad "7" smd rect
			(at -0.32512 -1.6256 270)
			(size 0.3556 1.524)
			(layers "F.Cu" "F.Mask" "F.Paste")
			(net "P3V3_STBY_A")
		)
		(pad "8" smd rect
			(at -0.97536 -1.6256 270)
			(size 0.3556 1.524)
			(layers "F.Cu" "F.Mask" "F.Paste")
			(net "DEBUG_CARD_A_PRSNT")
		)
	)
	(footprint ""
		(layer "F.Cu")
		(at 13.3096 -44.1452 180)
		(property "Reference" "R34"
			(at 0 0 180)
			(layer "F.SilkS")
			(hide yes)
			(effects
				(font
					(size 1.27 1.27)
				)
			)
		)
		(property "Value" "4K7R2F-GP"
			(at 0.064008 -4.679696 180)
			(unlocked yes)
			(layer "F.Fab")
			(hide yes)
			(effects
				(font
					(size 2.54 2.54)
					(thickness 0.381)
				)
			)
		)
		(property "Device Type" "R402H16"
			(at 0.064008 -6.203696 180)
			(unlocked yes)
			(layer "F.Fab")
			(hide yes)
			(effects
				(font
					(size 2.54 2.54)
					(thickness 0.381)
				)
			)
		)
		(duplicate_pad_numbers_are_jumpers no)
		(fp_line
			(start 0.508 -0.9398)
			(end -0.508 -0.9398)
			(stroke
				(width 0.1524)
				(type default)
			)
			(layer "F.SilkS")
		)
		(fp_line
			(start -0.508 -0.9398)
			(end -0.508 0.9398)
			(stroke
				(width 0.1524)
				(type default)
			)
			(layer "F.SilkS")
		)
		(fp_rect
			(start -0.508 0.9398)
			(end 0.508 -0.9398)
			(stroke
				(width 0)
				(type default)
			)
			(fill no)
			(layer "F.CrtYd")
		)
		(fp_rect
			(start -0.508 0.9398)
			(end 0.508 -0.9398)
			(stroke
				(width 0)
				(type default)
			)
			(fill no)
			(layer "F.Fab")
		)
		(pad "1" smd custom
			(at 0 -0.4445 180)
			(size 0.1397 0.1397)
			(layers "F.Cu" "F.Mask" "F.Paste")
			(net "P3V3_STBY_A")
			(options
				(clearance outline)
				(anchor circle)
			)
			(primitives
				(gr_poly
					(pts
						(arc
							(start -0.1778 -0.2794)
							(mid -0.249642 -0.249642)
							(end -0.2794 -0.1778)
						)
						(arc
							(start -0.2794 0.1778)
							(mid -0.249642 0.249642)
							(end -0.1778 0.2794)
						)
						(arc
							(start 0.1778 0.2794)
							(mid 0.249642 0.249642)
							(end 0.2794 0.1778)
						)
						(arc
							(start 0.2794 -0.1778)
							(mid 0.249642 -0.249642)
							(end 0.1778 -0.2794)
						)
					)
					(width 0)
					(fill yes)
				)
			)
		)
		(pad "2" smd custom
			(at 0 0.4445 180)
			(size 0.1397 0.1397)
			(layers "F.Cu" "F.Mask" "F.Paste")
			(net "TEMP_1_A2")
			(options
				(clearance outline)
				(anchor circle)
			)
			(primitives
				(gr_poly
					(pts
						(arc
							(start -0.1778 -0.2794)
							(mid -0.249642 -0.249642)
							(end -0.2794 -0.1778)
						)
						(arc
							(start -0.2794 0.1778)
							(mid -0.249642 0.249642)
							(end -0.1778 0.2794)
						)
						(arc
							(start 0.1778 0.2794)
							(mid 0.249642 0.249642)
							(end 0.2794 0.1778)
						)
						(arc
							(start 0.2794 -0.1778)
							(mid 0.249642 -0.249642)
							(end 0.1778 -0.2794)
						)
					)
					(width 0)
					(fill yes)
				)
			)
		)
	)
	(footprint ""
		(layer "F.Cu")
		(at 42.545 -14.478 -90)
		(property "Reference" "U14"
			(at 0 0 270)
			(layer "F.SilkS")
			(hide yes)
			(effects
				(font
					(size 1.27 1.27)
				)
			)
		)
		(property "Value" "SNLVC1G126DCKR-GP"
			(at -2.3368 -8.6868 270)
			(unlocked yes)
			(layer "F.Fab")
			(hide yes)
			(effects
				(font
					(size 1.016 1.016)
					(thickness 0.1524)
				)
			)
		)
		(property "Device Type" "SC70-5H44"
			(at -2.3114 -10.414 270)
			(unlocked yes)
			(layer "F.Fab")
			(hide yes)
			(effects
				(font
					(size 1.016 1.016)
					(thickness 0.1524)
				)
			)
		)
		(duplicate_pad_numbers_are_jumpers no)
		(fp_line
			(start -1.27 1.7018)
			(end -1.27 -1.7018)
			(stroke
				(width 0.1524)
				(type default)
			)
			(layer "F.SilkS")
		)
		(fp_line
			(start 1.27 1.7018)
			(end -1.27 1.7018)
			(stroke
				(width 0.1524)
				(type default)
			)
			(layer "F.SilkS")
		)
		(fp_line
			(start -1.27 -1.7018)
			(end 1.27 -1.7018)
			(stroke
				(width 0.1524)
				(type default)
			)
			(layer "F.SilkS")
		)
		(fp_line
			(start 1.27 -1.7018)
			(end 1.27 1.7018)
			(stroke
				(width 0.1524)
				(type default)
			)
			(layer "F.SilkS")
		)
		(fp_line
			(start 0.6604 -1.8034)
			(end 1.3843 -1.8034)
			(stroke
				(width 0.3302)
				(type default)
			)
			(layer "F.SilkS")
		)
		(fp_line
			(start 1.3843 -1.8034)
			(end 1.3843 -1.1176)
			(stroke
				(width 0.3302)
				(type default)
			)
			(layer "F.SilkS")
		)
		(fp_rect
			(start -1.524 1.9558)
			(end 1.524 -1.9558)
			(stroke
				(width 0)
				(type default)
			)
			(fill no)
			(layer "F.CrtYd")
		)
		(fp_poly
			(pts
				(xy -1.524 -1.9558) (xy 1.524 -1.9558) (xy 1.524 1.9558) (xy -1.524 1.9558)
			)
			(stroke
				(width 0)
				(type default)
			)
			(fill no)
			(layer "F.Fab")
		)
		(pad "1" smd rect
			(at 0.65024 -0.8255 270)
			(size 0.4064 1.2192)
			(layers "F.Cu" "F.Mask" "F.Paste")
			(net "DEBUG_CARD_B_PRSNT")
		)
		(pad "2" smd rect
			(at 0 -0.8255 270)
			(size 0.4064 1.2192)
			(layers "F.Cu" "F.Mask" "F.Paste")
			(net "UART_DEBUG_B_RX")
		)
		(pad "3" smd rect
			(at -0.65024 -0.8255 270)
			(size 0.4064 1.2192)
			(layers "F.Cu" "F.Mask" "F.Paste")
			(net "GND")
		)
		(pad "4" smd rect
			(at -0.65024 0.8255 270)
			(size 0.4064 1.2192)
			(layers "F.Cu" "F.Mask" "F.Paste")
			(net "UART_B_RX")
		)
		(pad "5" smd rect
			(at 0.65024 0.8255 270)
			(size 0.4064 1.2192)
			(layers "F.Cu" "F.Mask" "F.Paste")
			(net "P3V3_STBY_B")
		)
	)
	(footprint ""
		(layer "F.Cu")
		(at 52.4002 -26.797 90)
		(property "Reference" "U16"
			(at 0 0 90)
			(layer "F.SilkS")
			(hide yes)
			(effects
				(font
					(size 1.27 1.27)
				)
			)
		)
		(property "Value" "SN74LVC1G08DCKR-GP"
			(at -2.3368 -8.6868 90)
			(unlocked yes)
			(layer "F.Fab")
			(hide yes)
			(effects
				(font
					(size 1.016 1.016)
					(thickness 0.1524)
				)
			)
		)
		(property "Device Type" "SC70-5H44"
			(at -2.3114 -10.414 90)
			(unlocked yes)
			(layer "F.Fab")
			(hide yes)
			(effects
				(font
					(size 1.016 1.016)
					(thickness 0.1524)
				)
			)
		)
		(duplicate_pad_numbers_are_jumpers no)
		(fp_line
			(start 1.3843 -1.8034)
			(end 1.3843 -1.1176)
			(stroke
				(width 0.3302)
				(type default)
			)
			(layer "F.SilkS")
		)
		(fp_line
			(start 0.6604 -1.8034)
			(end 1.3843 -1.8034)
			(stroke
				(width 0.3302)
				(type default)
			)
			(layer "F.SilkS")
		)
		(fp_line
			(start 1.27 -1.7018)
			(end 1.27 1.7018)
			(stroke
				(width 0.1524)
				(type default)
			)
			(layer "F.SilkS")
		)
		(fp_line
			(start -1.27 -1.7018)
			(end 1.27 -1.7018)
			(stroke
				(width 0.1524)
				(type default)
			)
			(layer "F.SilkS")
		)
		(fp_line
			(start 1.27 1.7018)
			(end -1.27 1.7018)
			(stroke
				(width 0.1524)
				(type default)
			)
			(layer "F.SilkS")
		)
		(fp_line
			(start -1.27 1.7018)
			(end -1.27 -1.7018)
			(stroke
				(width 0.1524)
				(type default)
			)
			(layer "F.SilkS")
		)
		(fp_rect
			(start -1.524 1.9558)
			(end 1.524 -1.9558)
			(stroke
				(width 0)
				(type default)
			)
			(fill no)
			(layer "F.CrtYd")
		)
		(fp_poly
			(pts
				(xy -1.524 -1.9558) (xy 1.524 -1.9558) (xy 1.524 1.9558) (xy -1.524 1.9558)
			)
			(stroke
				(width 0)
				(type default)
			)
			(fill no)
			(layer "F.Fab")
		)
		(pad "1" smd rect
			(at 0.65024 -0.8255 90)
			(size 0.4064 1.2192)
			(layers "F.Cu" "F.Mask" "F.Paste")
			(net "SYS_RESET_BTN_B_N_R")
		)
		(pad "2" smd rect
			(at 0 -0.8255 90)
			(size 0.4064 1.2192)
			(layers "F.Cu" "F.Mask" "F.Paste")
			(net "DEBUG_RST_B_BTN_N")
		)
		(pad "3" smd rect
			(at -0.65024 -0.8255 90)
			(size 0.4064 1.2192)
			(layers "F.Cu" "F.Mask" "F.Paste")
			(net "GND")
		)
		(pad "4" smd rect
			(at -0.65024 0.8255 90)
			(size 0.4064 1.2192)
			(layers "F.Cu" "F.Mask" "F.Paste")
			(net "SYS_RESET_BTN_B_N")
		)
		(pad "5" smd rect
			(at 0.65024 0.8255 90)
			(size 0.4064 1.2192)
			(layers "F.Cu" "F.Mask" "F.Paste")
			(net "P3V3_STBY_B")
		)
	)
	(footprint ""
		(layer "F.Cu")
		(at 2.671826 -55.22849 90)
		(property "Reference" "TP1"
			(at 0 0 90)
			(layer "F.SilkS")
			(hide yes)
			(effects
				(font
					(size 1.27 1.27)
				)
			)
		)
		(property "Value" "TPAD28-2-GP"
			(at -0.0127 -2.3495 90)
			(unlocked yes)
			(layer "F.Fab")
			(hide yes)
			(effects
				(font
					(size 2.54 2.54)
					(thickness 0.381)
				)
			)
		)
		(property "Device Type" "TPAD28"
			(at -0.0127 -3.8735 90)
			(unlocked yes)
			(layer "F.Fab")
			(hide yes)
			(effects
				(font
					(size 2.54 2.54)
					(thickness 0.381)
				)
			)
		)
		(duplicate_pad_numbers_are_jumpers no)
		(fp_poly
			(pts
				(arc
					(start 0 0.3556)
					(mid 0 -0.3556)
					(end 0 0.3556)
				)
			)
			(stroke
				(width 0)
				(type default)
			)
			(fill no)
			(layer "F.CrtYd")
		)
		(fp_poly
			(pts
				(arc
					(start 0 0.6096)
					(mid 0 -0.6096)
					(end 0 0.6096)
				)
			)
			(stroke
				(width 0)
				(type default)
			)
			(fill no)
			(layer "F.Fab")
		)
		(pad "1" smd circle
			(at 0 0 90)
			(size 0.7112 0.7112)
			(layers "F.Cu" "F.Mask" "F.Paste")
			(net "DEBUG_USB_A_DN")
		)
	)
	(footprint ""
		(layer "F.Cu")
		(at 12.769088 -72.840088 180)
		(property "Reference" "R15"
			(at 0 0 180)
			(layer "F.SilkS")
			(hide yes)
			(effects
				(font
					(size 1.27 1.27)
				)
			)
		)
		(property "Value" "200R2J-L1-GP"
			(at 0.064008 -4.679696 180)
			(unlocked yes)
			(layer "F.Fab")
			(hide yes)
			(effects
				(font
					(size 2.54 2.54)
					(thickness 0.381)
				)
			)
		)
		(property "Device Type" "R402H16"
			(at 0.064008 -6.203696 180)
			(unlocked yes)
			(layer "F.Fab")
			(hide yes)
			(effects
				(font
					(size 2.54 2.54)
					(thickness 0.381)
				)
			)
		)
		(duplicate_pad_numbers_are_jumpers no)
		(fp_line
			(start 0.508 -0.9398)
			(end -0.508 -0.9398)
			(stroke
				(width 0.1524)
				(type default)
			)
			(layer "F.SilkS")
		)
		(fp_line
			(start -0.508 -0.9398)
			(end -0.508 0.9398)
			(stroke
				(width 0.1524)
				(type default)
			)
			(layer "F.SilkS")
		)
		(fp_rect
			(start -0.508 0.9398)
			(end 0.508 -0.9398)
			(stroke
				(width 0)
				(type default)
			)
			(fill no)
			(layer "F.CrtYd")
		)
		(fp_rect
			(start -0.508 0.9398)
			(end 0.508 -0.9398)
			(stroke
				(width 0)
				(type default)
			)
			(fill no)
			(layer "F.Fab")
		)
		(pad "1" smd custom
			(at 0 -0.4445 180)
			(size 0.1397 0.1397)
			(layers "F.Cu" "F.Mask" "F.Paste")
			(net "P5V_USB_A")
			(options
				(clearance outline)
				(anchor circle)
			)
			(primitives
				(gr_poly
					(pts
						(arc
							(start -0.1778 -0.2794)
							(mid -0.249642 -0.249642)
							(end -0.2794 -0.1778)
						)
						(arc
							(start -0.2794 0.1778)
							(mid -0.249642 0.249642)
							(end -0.1778 0.2794)
						)
						(arc
							(start 0.1778 0.2794)
							(mid 0.249642 0.249642)
							(end 0.2794 0.1778)
						)
						(arc
							(start 0.2794 -0.1778)
							(mid 0.249642 -0.249642)
							(end 0.1778 -0.2794)
						)
					)
					(width 0)
					(fill yes)
				)
			)
		)
		(pad "2" smd custom
			(at 0 0.4445 180)
			(size 0.1397 0.1397)
			(layers "F.Cu" "F.Mask" "F.Paste")
			(net "PWR_BTN_LED_A_R")
			(options
				(clearance outline)
				(anchor circle)
			)
			(primitives
				(gr_poly
					(pts
						(arc
							(start -0.1778 -0.2794)
							(mid -0.249642 -0.249642)
							(end -0.2794 -0.1778)
						)
						(arc
							(start -0.2794 0.1778)
							(mid -0.249642 0.249642)
							(end -0.1778 0.2794)
						)
						(arc
							(start 0.1778 0.2794)
							(mid 0.249642 0.249642)
							(end 0.2794 0.1778)
						)
						(arc
							(start 0.2794 -0.1778)
							(mid 0.249642 -0.249642)
							(end 0.1778 -0.2794)
						)
					)
					(width 0)
					(fill yes)
				)
			)
		)
	)
	(footprint ""
		(layer "F.Cu")
		(at 48.387 -22.86 90)
		(property "Reference" "R78"
			(at 0 0 90)
			(layer "F.SilkS")
			(hide yes)
			(effects
				(font
					(size 1.27 1.27)
				)
			)
		)
		(property "Value" "4K7R2F-GP"
			(at 0.064008 -3.993896 90)
			(unlocked yes)
			(layer "F.Fab")
			(hide yes)
			(effects
				(font
					(size 1.016 1.016)
					(thickness 0.1524)
				)
			)
		)
		(property "Device Type" "R402H16"
			(at 0.064008 -5.517896 90)
			(unlocked yes)
			(layer "F.Fab")
			(hide yes)
			(effects
				(font
					(size 1.016 1.016)
					(thickness 0.1524)
				)
			)
		)
		(duplicate_pad_numbers_are_jumpers no)
		(fp_line
			(start 0.508 -0.9398)
			(end -0.508 -0.9398)
			(stroke
				(width 0.1524)
				(type default)
			)
			(layer "F.SilkS")
		)
		(fp_line
			(start -0.508 -0.9398)
			(end -0.508 0.9398)
			(stroke
				(width 0.1524)
				(type default)
			)
			(layer "F.SilkS")
		)
		(fp_rect
			(start -0.508 0.9398)
			(end 0.508 -0.9398)
			(stroke
				(width 0)
				(type default)
			)
			(fill no)
			(layer "F.CrtYd")
		)
		(fp_rect
			(start -0.508 0.9398)
			(end 0.508 -0.9398)
			(stroke
				(width 0)
				(type default)
			)
			(fill no)
			(layer "F.Fab")
		)
		(pad "1" smd custom
			(at 0 -0.4445 90)
			(size 0.1397 0.1397)
			(layers "F.Cu" "F.Mask" "F.Paste")
			(net "P3V3_STBY_B")
			(options
				(clearance outline)
				(anchor circle)
			)
			(primitives
				(gr_poly
					(pts
						(arc
							(start -0.1778 -0.2794)
							(mid -0.249642 -0.249642)
							(end -0.2794 -0.1778)
						)
						(arc
							(start -0.2794 0.1778)
							(mid -0.249642 0.249642)
							(end -0.1778 0.2794)
						)
						(arc
							(start 0.1778 0.2794)
							(mid 0.249642 0.249642)
							(end 0.2794 0.1778)
						)
						(arc
							(start 0.2794 -0.1778)
							(mid 0.249642 -0.249642)
							(end 0.1778 -0.2794)
						)
					)
					(width 0)
					(fill yes)
				)
			)
		)
		(pad "2" smd custom
			(at 0 0.4445 90)
			(size 0.1397 0.1397)
			(layers "F.Cu" "F.Mask" "F.Paste")
			(net "DEBUG_RST_B_BTN_N")
			(options
				(clearance outline)
				(anchor circle)
			)
			(primitives
				(gr_poly
					(pts
						(arc
							(start -0.1778 -0.2794)
							(mid -0.249642 -0.249642)
							(end -0.2794 -0.1778)
						)
						(arc
							(start -0.2794 0.1778)
							(mid -0.249642 0.249642)
							(end -0.1778 0.2794)
						)
						(arc
							(start 0.1778 0.2794)
							(mid 0.249642 0.249642)
							(end 0.2794 0.1778)
						)
						(arc
							(start 0.2794 -0.1778)
							(mid 0.249642 -0.249642)
							(end 0.1778 -0.2794)
						)
					)
					(width 0)
					(fill yes)
				)
			)
		)
	)
)
